(kicad_pcb
	(version 20241229)
	(generator "pcbnew")
	(generator_version "9.0")
	(general
		(thickness 1.6642)
		(legacy_teardrops no)
	)
	(paper "A3")
	(title_block
		(title "PolarFire SoM")
		(date "2025-07-22")
		(rev "1.1.4")
		(company "Antmicro Ltd")
		(comment 1 "www.antmicro.com")
		(comment 9 "footprints 284-288 of 470")
	)
	(layers
		(0 "F.Cu" mixed)
		(4 "In1.Cu" power)
		(6 "In2.Cu" signal)
		(8 "In3.Cu" power)
		(10 "In4.Cu" signal)
		(12 "In5.Cu" power)
		(14 "In6.Cu" power)
		(16 "In7.Cu" signal)
		(18 "In8.Cu" power)
		(20 "In9.Cu" signal)
		(22 "In10.Cu" power)
		(24 "In11.Cu" signal)
		(26 "In12.Cu" signal)
		(2 "B.Cu" mixed)
		(9 "F.Adhes" user "F.Adhesive")
		(11 "B.Adhes" user "B.Adhesive")
		(13 "F.Paste" user)
		(15 "B.Paste" user)
		(5 "F.SilkS" user "F.Silkscreen")
		(7 "B.SilkS" user "B.Silkscreen")
		(1 "F.Mask" user)
		(3 "B.Mask" user)
		(17 "Dwgs.User" user "User.Drawings")
		(19 "Cmts.User" user "User.Comments")
		(21 "Eco1.User" user "User.Eco1")
		(23 "Eco2.User" user "User.Eco2")
		(25 "Edge.Cuts" user)
		(27 "Margin" user)
		(31 "F.CrtYd" user "F.Courtyard")
		(29 "B.CrtYd" user "B.Courtyard")
		(35 "F.Fab" user)
		(33 "B.Fab" user)
	)
	(footprint "antmicro-footprints:R_0402_1005Metric"
		(layer "B.Cu")
		(at 224.33 128.2 180)
		(descr "Resistor SMD 0402")
		(tags "resistor SMD 0402")
		(property "Reference" "R71"
			(at -1.62 0.45 0)
			(layer "B.SilkS")
			(effects
				(font
					(size 0.7 0.7)
					(thickness 0.15)
				)
				(justify left bottom mirror)
			)
		)
		(property "Value" "R_470R_0402"
			(at -1.011843 -1.772047 0)
			(layer "B.Fab")
			(hide yes)
			(effects
				(font
					(size 0.7 0.7)
					(thickness 0.15)
				)
				(justify left bottom mirror)
			)
		)
		(property "Datasheet" "https://www.bourns.com/docs/product-datasheets/cr.pdf"
			(at 0 0 180)
			(layer "F.Fab")
			(hide yes)
			(effects
				(font
					(size 1.27 1.27)
					(thickness 0.15)
				)
			)
		)
		(property "Description" "SMD Chip Resistor, 470 ohm, ± 1%, 62.5 mW, 0402 [1005 Metric], Thick Film, General Purpose"
			(at 0 0 180)
			(layer "F.Fab")
			(hide yes)
			(effects
				(font
					(size 1.27 1.27)
					(thickness 0.15)
				)
			)
		)
		(property "Author" "Antmicro"
			(at 448.66 256.4 0)
			(layer "B.Fab")
			(hide yes)
			(effects
				(font
					(size 1 1)
					(thickness 0.15)
				)
				(justify mirror)
			)
		)
		(property "License" "Apache-2.0"
			(at 448.66 256.4 0)
			(layer "B.Fab")
			(hide yes)
			(effects
				(font
					(size 1 1)
					(thickness 0.15)
				)
				(justify mirror)
			)
		)
		(property "MPN" "CR0402-FX-4700GLF"
			(at 448.66 256.4 0)
			(layer "B.Fab")
			(hide yes)
			(effects
				(font
					(size 1 1)
					(thickness 0.15)
				)
				(justify mirror)
			)
		)
		(property "Manufacturer" "Bourns"
			(at 448.66 256.4 0)
			(layer "B.Fab")
			(hide yes)
			(effects
				(font
					(size 1 1)
					(thickness 0.15)
				)
				(justify mirror)
			)
		)
		(property "Public" ""
			(at 448.66 256.4 0)
			(layer "B.Fab")
			(hide yes)
			(effects
				(font
					(size 1 1)
					(thickness 0.15)
				)
				(justify mirror)
			)
		)
		(property "Tolerance" "1%"
			(at 448.66 256.4 0)
			(layer "B.Fab")
			(hide yes)
			(effects
				(font
					(size 1 1)
					(thickness 0.15)
				)
				(justify mirror)
			)
		)
		(property "Val" "470R"
			(at 448.66 256.4 0)
			(layer "B.Fab")
			(hide yes)
			(effects
				(font
					(size 1 1)
					(thickness 0.15)
				)
				(justify mirror)
			)
		)
		(sheetname "/FPGA GPIO/")
		(sheetfile "fpga-gpio.kicad_sch")
		(attr smd)
		(fp_rect
			(start -0.925 0.47)
			(end 0.925 -0.47)
			(stroke
				(width 0.05)
				(type default)
			)
			(fill no)
			(layer "B.CrtYd")
		)
		(fp_rect
			(start -0.5 0.25)
			(end 0.5 -0.25)
			(stroke
				(width 0.15)
				(type solid)
			)
			(fill no)
			(layer "B.Fab")
		)
		(fp_text user "License: Apache-2.0"
			(at -0.95 -5.169 0)
			(layer "B.Fab")
			(effects
				(font
					(size 0.7 0.7)
					(thickness 0.15)
				)
				(justify left bottom mirror)
			)
		)
		(fp_text user "Author: Antmicro"
			(at -0.95 -4.169 0)
			(layer "B.Fab")
			(effects
				(font
					(size 0.7 0.7)
					(thickness 0.15)
				)
				(justify left bottom mirror)
			)
		)
		(fp_text user "${REFERENCE}"
			(at -0.95 -3.168 0)
			(layer "B.Fab")
			(effects
				(font
					(size 0.7 0.7)
					(thickness 0.15)
				)
				(justify left bottom mirror)
			)
		)
		(pad "1" smd roundrect
			(at -0.48 0 180)
			(size 0.59 0.64)
			(layers "B.Cu" "B.Mask" "B.Paste")
			(roundrect_rratio 0.25)
			(net 541 "Net-(Q7-D)")
			(pintype "passive")
		)
		(pad "2" smd roundrect
			(at 0.48 0 180)
			(size 0.59 0.64)
			(layers "B.Cu" "B.Mask" "B.Paste")
			(roundrect_rratio 0.25)
			(net 538 "Net-(D6-C_{G})")
			(pintype "passive")
		)
	)
	(footprint "antmicro-footprints:C_0402_1005Metric"
		(layer "B.Cu")
		(at 177.65 147.35 90)
		(descr "Capacitor SMD 0402")
		(tags "capacitor SMD 0402")
		(property "Reference" "C84"
			(at -3.29 1.39 90)
			(layer "B.SilkS")
			(effects
				(font
					(size 0.7 0.7)
					(thickness 0.15)
				)
				(justify right bottom mirror)
			)
		)
		(property "Value" "C_100n_0402"
			(at -1.022927 -2.155213 90)
			(layer "B.Fab")
			(hide yes)
			(effects
				(font
					(size 0.7 0.7)
					(thickness 0.15)
				)
				(justify right bottom mirror)
			)
		)
		(property "Datasheet" "https://www.murata.com/products/productdetail?partno=GRM155R61H104KE14%23"
			(at 0 0 90)
			(layer "F.Fab")
			(hide yes)
			(effects
				(font
					(size 1.27 1.27)
					(thickness 0.15)
				)
			)
		)
		(property "Description" "SMD Multilayer Ceramic Capacitor, 0.1 µF, 50 V, 0402 [1005 Metric], ± 10%, X5R, GRM Series"
			(at 0 0 90)
			(layer "F.Fab")
			(hide yes)
			(effects
				(font
					(size 1.27 1.27)
					(thickness 0.15)
				)
			)
		)
		(property "Author" "Antmicro"
			(at 325 -30.3 0)
			(layer "B.Fab")
			(hide yes)
			(effects
				(font
					(size 1 1)
					(thickness 0.15)
				)
				(justify mirror)
			)
		)
		(property "Dielectric" "X5R"
			(at 325 -30.3 0)
			(layer "B.Fab")
			(hide yes)
			(effects
				(font
					(size 1 1)
					(thickness 0.15)
				)
				(justify mirror)
			)
		)
		(property "License" "Apache-2.0"
			(at 325 -30.3 0)
			(layer "B.Fab")
			(hide yes)
			(effects
				(font
					(size 1 1)
					(thickness 0.15)
				)
				(justify mirror)
			)
		)
		(property "MPN" "GRM155R61H104KE14D"
			(at 325 -30.3 0)
			(layer "B.Fab")
			(hide yes)
			(effects
				(font
					(size 1 1)
					(thickness 0.15)
				)
				(justify mirror)
			)
		)
		(property "Manufacturer" "Murata"
			(at 325 -30.3 0)
			(layer "B.Fab")
			(hide yes)
			(effects
				(font
					(size 1 1)
					(thickness 0.15)
				)
				(justify mirror)
			)
		)
		(property "Public" ""
			(at 325 -30.3 0)
			(layer "B.Fab")
			(hide yes)
			(effects
				(font
					(size 1 1)
					(thickness 0.15)
				)
				(justify mirror)
			)
		)
		(property "Val" "100n"
			(at 325 -30.3 0)
			(layer "B.Fab")
			(hide yes)
			(effects
				(font
					(size 1 1)
					(thickness 0.15)
				)
				(justify mirror)
			)
		)
		(property "Voltage" "50V"
			(at 325 -30.3 0)
			(layer "B.Fab")
			(hide yes)
			(effects
				(font
					(size 1 1)
					(thickness 0.15)
				)
				(justify mirror)
			)
		)
		(sheetname "/Supply/")
		(sheetfile "supply.kicad_sch")
		(attr smd)
		(fp_rect
			(start -0.925 0.47)
			(end 0.925 -0.47)
			(stroke
				(width 0.05)
				(type default)
			)
			(fill no)
			(layer "B.CrtYd")
		)
		(fp_line
			(start 0.504 -0.248)
			(end -0.494 -0.248)
			(stroke
				(width 0.15)
				(type solid)
			)
			(layer "B.Fab")
		)
		(fp_line
			(start -0.494 -0.248)
			(end -0.494 0.25)
			(stroke
				(width 0.15)
				(type solid)
			)
			(layer "B.Fab")
		)
		(fp_line
			(start 0.504 0.25)
			(end 0.504 -0.248)
			(stroke
				(width 0.15)
				(type solid)
			)
			(layer "B.Fab")
		)
		(fp_line
			(start -0.494 0.25)
			(end 0.504 0.25)
			(stroke
				(width 0.15)
				(type solid)
			)
			(layer "B.Fab")
		)
		(fp_text user "${REFERENCE}"
			(at -0.939 -4.599 270)
			(layer "B.Fab")
			(effects
				(font
					(size 0.7 0.7)
					(thickness 0.15)
				)
				(justify left bottom mirror)
			)
		)
		(fp_text user "License: Apache-2.0"
			(at -0.939 -5.799 270)
			(layer "B.Fab")
			(effects
				(font
					(size 0.7 0.7)
					(thickness 0.15)
				)
				(justify left bottom mirror)
			)
		)
		(fp_text user "Author: Antmicro"
			(at -0.939 -3.399 270)
			(layer "B.Fab")
			(effects
				(font
					(size 0.7 0.7)
					(thickness 0.15)
				)
				(justify left bottom mirror)
			)
		)
		(pad "1" smd roundrect
			(at -0.48 0 90)
			(size 0.59 0.64)
			(layers "B.Cu" "B.Mask" "B.Paste")
			(roundrect_rratio 0.25)
			(net 417 "GND")
			(pintype "passive")
		)
		(pad "2" smd roundrect
			(at 0.48 0 90)
			(size 0.59 0.64)
			(layers "B.Cu" "B.Mask" "B.Paste")
			(roundrect_rratio 0.25)
			(net 50 "+3V3")
			(pintype "passive")
		)
	)
	(footprint "antmicro-footprints:TP_SMD_0.75mm"
		(layer "B.Cu")
		(at 186.125 149.525 180)
		(property "Reference" "TP21"
			(at -1.175 -1.325 180)
			(layer "B.SilkS")
			(hide yes)
			(effects
				(font
					(size 0.7 0.7)
					(thickness 0.15)
				)
				(justify left bottom mirror)
			)
		)
		(property "Value" "TP_0.75mm_SMD"
			(at 0 -1.2 0)
			(layer "B.Fab")
			(hide yes)
			(effects
				(font
					(size 0.7 0.7)
					(thickness 0.15)
				)
				(justify left bottom mirror)
			)
		)
		(property "Description" "SMT test point"
			(at 0 0 0)
			(layer "B.Fab")
			(hide yes)
			(effects
				(font
					(size 1.27 1.27)
					(thickness 0.15)
				)
				(justify mirror)
			)
		)
		(property "MPN" ""
			(at 0 0 0)
			(unlocked yes)
			(layer "B.Fab")
			(hide yes)
			(effects
				(font
					(size 1 1)
					(thickness 0.15)
				)
				(justify mirror)
			)
		)
		(property "Manufacturer" ""
			(at 0 0 0)
			(unlocked yes)
			(layer "B.Fab")
			(hide yes)
			(effects
				(font
					(size 1 1)
					(thickness 0.15)
				)
				(justify mirror)
			)
		)
		(property "Author" "Antmicro"
			(at 0 0 0)
			(unlocked yes)
			(layer "B.Fab")
			(hide yes)
			(effects
				(font
					(size 1 1)
					(thickness 0.15)
				)
				(justify mirror)
			)
		)
		(property "License" "Apache-2.0"
			(at 0 0 0)
			(unlocked yes)
			(layer "B.Fab")
			(hide yes)
			(effects
				(font
					(size 1 1)
					(thickness 0.15)
				)
				(justify mirror)
			)
		)
		(property "Public" "False"
			(at 0 0 0)
			(unlocked yes)
			(layer "B.Fab")
			(hide yes)
			(effects
				(font
					(size 1 1)
					(thickness 0.15)
				)
				(justify mirror)
			)
		)
		(sheetname "/Supply/")
		(sheetfile "supply.kicad_sch")
		(attr exclude_from_pos_files exclude_from_bom)
		(fp_circle
			(center 0 0)
			(end 0.475 0)
			(stroke
				(width 0.05)
				(type default)
			)
			(fill no)
			(layer "B.CrtYd")
		)
		(fp_text user "Author: Antmicro"
			(at -0.4 -3.901 0)
			(layer "B.Fab")
			(effects
				(font
					(size 0.7 0.7)
					(thickness 0.15)
				)
				(justify left bottom mirror)
			)
		)
		(fp_text user "License: Apache-2.0"
			(at -0.4 -5.101 0)
			(layer "B.Fab")
			(effects
				(font
					(size 0.7 0.7)
					(thickness 0.15)
				)
				(justify left bottom mirror)
			)
		)
		(fp_text user "${REFERENCE}"
			(at -0.4 -2.7 0)
			(layer "B.Fab")
			(effects
				(font
					(size 0.7 0.7)
					(thickness 0.15)
				)
				(justify left bottom mirror)
			)
		)
		(pad "1" smd circle
			(at 0 0 180)
			(size 0.75 0.75)
			(layers "B.Cu" "B.Mask")
			(net 633 "Net-(U7-OUT4)")
			(pinfunction "1")
			(pintype "passive")
		)
	)
	(footprint "antmicro-footprints:C_0402_1005Metric"
		(layer "B.Cu")
		(at 175.28 126.8655 -90)
		(descr "Capacitor SMD 0402")
		(tags "capacitor SMD 0402")
		(property "Reference" "C145"
			(at 0.3945 -2.39 135)
			(layer "B.SilkS")
			(effects
				(font
					(size 0.7 0.7)
					(thickness 0.15)
				)
				(justify left bottom mirror)
			)
		)
		(property "Value" "C_1u_0402"
			(at -1.022927 -2.155213 90)
			(layer "B.Fab")
			(hide yes)
			(effects
				(font
					(size 0.7 0.7)
					(thickness 0.15)
				)
				(justify left bottom mirror)
			)
		)
		(property "Datasheet" "https://product.tdk.com/en/search/capacitor/ceramic/mlcc/info?part_no=C1005X6S1A105K050BC"
			(at 0 0 270)
			(layer "F.Fab")
			(hide yes)
			(effects
				(font
					(size 1.27 1.27)
					(thickness 0.15)
				)
			)
		)
		(property "Description" "SMD Multilayer Ceramic Capacitor, 1 µF, 10 V, 0402 [1005 Metric], ± 10%, X6S, C"
			(at 0 0 270)
			(layer "F.Fab")
			(hide yes)
			(effects
				(font
					(size 1.27 1.27)
					(thickness 0.15)
				)
			)
		)
		(property "Author" "Antmicro"
			(at 48.4145 302.1455 0)
			(layer "B.Fab")
			(hide yes)
			(effects
				(font
					(size 1 1)
					(thickness 0.15)
				)
				(justify mirror)
			)
		)
		(property "Dielectric" "X5R"
			(at 48.4145 302.1455 0)
			(layer "B.Fab")
			(hide yes)
			(effects
				(font
					(size 1 1)
					(thickness 0.15)
				)
				(justify mirror)
			)
		)
		(property "License" "Apache-2.0"
			(at 48.4145 302.1455 0)
			(layer "B.Fab")
			(hide yes)
			(effects
				(font
					(size 1 1)
					(thickness 0.15)
				)
				(justify mirror)
			)
		)
		(property "MPN" "C1005X6S1A105K050BC"
			(at 48.4145 302.1455 0)
			(layer "B.Fab")
			(hide yes)
			(effects
				(font
					(size 1 1)
					(thickness 0.15)
				)
				(justify mirror)
			)
		)
		(property "Manufacturer" "TDK"
			(at 48.4145 302.1455 0)
			(layer "B.Fab")
			(hide yes)
			(effects
				(font
					(size 1 1)
					(thickness 0.15)
				)
				(justify mirror)
			)
		)
		(property "Public" ""
			(at 48.4145 302.1455 0)
			(layer "B.Fab")
			(hide yes)
			(effects
				(font
					(size 1 1)
					(thickness 0.15)
				)
				(justify mirror)
			)
		)
		(property "Val" "1u"
			(at 48.4145 302.1455 0)
			(layer "B.Fab")
			(hide yes)
			(effects
				(font
					(size 1 1)
					(thickness 0.15)
				)
				(justify mirror)
			)
		)
		(property "Voltage" "16V"
			(at 48.4145 302.1455 0)
			(layer "B.Fab")
			(hide yes)
			(effects
				(font
					(size 1 1)
					(thickness 0.15)
				)
				(justify mirror)
			)
		)
		(sheetname "/LPDDR4/")
		(sheetfile "lpddr.kicad_sch")
		(attr smd)
		(fp_rect
			(start -0.925 0.47)
			(end 0.925 -0.47)
			(stroke
				(width 0.05)
				(type default)
			)
			(fill no)
			(layer "B.CrtYd")
		)
		(fp_line
			(start -0.494 0.25)
			(end 0.504 0.25)
			(stroke
				(width 0.15)
				(type solid)
			)
			(layer "B.Fab")
		)
		(fp_line
			(start 0.504 0.25)
			(end 0.504 -0.248)
			(stroke
				(width 0.15)
				(type solid)
			)
			(layer "B.Fab")
		)
		(fp_line
			(start -0.494 -0.248)
			(end -0.494 0.25)
			(stroke
				(width 0.15)
				(type solid)
			)
			(layer "B.Fab")
		)
		(fp_line
			(start 0.504 -0.248)
			(end -0.494 -0.248)
			(stroke
				(width 0.15)
				(type solid)
			)
			(layer "B.Fab")
		)
		(fp_text user "${REFERENCE}"
			(at -0.939 -4.599 90)
			(layer "B.Fab")
			(effects
				(font
					(size 0.7 0.7)
					(thickness 0.15)
				)
				(justify left bottom mirror)
			)
		)
		(fp_text user "License: Apache-2.0"
			(at -0.939 -5.799 90)
			(layer "B.Fab")
			(effects
				(font
					(size 0.7 0.7)
					(thickness 0.15)
				)
				(justify left bottom mirror)
			)
		)
		(fp_text user "Author: Antmicro"
			(at -0.939 -3.399 90)
			(layer "B.Fab")
			(effects
				(font
					(size 0.7 0.7)
					(thickness 0.15)
				)
				(justify left bottom mirror)
			)
		)
		(pad "1" smd roundrect
			(at -0.48 0 270)
			(size 0.59 0.64)
			(layers "B.Cu" "B.Mask" "B.Paste")
			(roundrect_rratio 0.25)
			(net 417 "GND")
			(pintype "passive")
		)
		(pad "2" smd roundrect
			(at 0.48 0 270)
			(size 0.59 0.64)
			(layers "B.Cu" "B.Mask" "B.Paste")
			(roundrect_rratio 0.25)
			(net 2 "+1V1")
			(pintype "passive")
		)
	)
	(footprint "antmicro-footprints:FB_0402_1005Metric"
		(layer "B.Cu")
		(at 192.92 145.3 180)
		(descr "Ferrite Bead SMD 0402")
		(tags "ferrite bead SMD 0402")
		(property "Reference" "FB4"
			(at -1.13 0.547484 0)
			(layer "B.SilkS")
			(effects
				(font
					(size 0.7 0.7)
					(thickness 0.15)
				)
				(justify left bottom mirror)
			)
		)
		(property "Value" "FB_120Z_1.2A_TDK-MPZ_0402"
			(at 0 -1.4 0)
			(layer "B.Fab")
			(hide yes)
			(effects
				(font
					(size 0.7 0.7)
					(thickness 0.15)
				)
				(justify left bottom mirror)
			)
		)
		(property "Datasheet" "https://product.tdk.com/en/search/emc/emc/beads/info?part_no=MPZ1005S121CT000"
			(at 0 0 180)
			(layer "F.Fab")
			(hide yes)
			(effects
				(font
					(size 1.27 1.27)
					(thickness 0.15)
				)
			)
		)
		(property "Description" "Ferrite Bead, 0402 [1005 Metric], 120 ohm, 1.2A, MPZ, 0.06 ohm, ± 25%, DC Power line"
			(at 0 0 180)
			(layer "F.Fab")
			(hide yes)
			(effects
				(font
					(size 1.27 1.27)
					(thickness 0.15)
				)
			)
		)
		(property "Author" "Antmicro"
			(at 385.84 290.6 0)
			(layer "B.Fab")
			(hide yes)
			(effects
				(font
					(size 1 1)
					(thickness 0.15)
				)
				(justify mirror)
			)
		)
		(property "Current" ""
			(at 385.84 290.6 0)
			(layer "B.Fab")
			(hide yes)
			(effects
				(font
					(size 1 1)
					(thickness 0.15)
				)
				(justify mirror)
			)
		)
		(property "License" "Apache-2.0"
			(at 385.84 290.6 0)
			(layer "B.Fab")
			(hide yes)
			(effects
				(font
					(size 1 1)
					(thickness 0.15)
				)
				(justify mirror)
			)
		)
		(property "MPN" "MPZ1005S121CT000"
			(at 385.84 290.6 0)
			(layer "B.Fab")
			(hide yes)
			(effects
				(font
					(size 1 1)
					(thickness 0.15)
				)
				(justify mirror)
			)
		)
		(property "Manufacturer" "TDK"
			(at 385.84 290.6 0)
			(layer "B.Fab")
			(hide yes)
			(effects
				(font
					(size 1 1)
					(thickness 0.15)
				)
				(justify mirror)
			)
		)
		(property "Public" ""
			(at 385.84 290.6 0)
			(layer "B.Fab")
			(hide yes)
			(effects
				(font
					(size 1 1)
					(thickness 0.15)
				)
				(justify mirror)
			)
		)
		(property "Val" "120Z/1.2A"
			(at 385.84 290.6 0)
			(layer "B.Fab")
			(hide yes)
			(effects
				(font
					(size 1 1)
					(thickness 0.15)
				)
				(justify mirror)
			)
		)
		(sheetname "/HDMI/")
		(sheetfile "hdmi.kicad_sch")
		(attr smd)
		(fp_rect
			(start -0.925 0.47)
			(end 0.925 -0.47)
			(stroke
				(width 0.05)
				(type default)
			)
			(fill no)
			(layer "B.CrtYd")
		)
		(fp_rect
			(start -0.5 0.25)
			(end 0.5 -0.25)
			(stroke
				(width 0.15)
				(type solid)
			)
			(fill no)
			(layer "B.Fab")
		)
		(fp_text user "License: Apache-2.0"
			(at -0.95 -5.169 0)
			(layer "B.Fab")
			(effects
				(font
					(size 0.7 0.7)
					(thickness 0.15)
				)
				(justify left bottom mirror)
			)
		)
		(fp_text user "Author: Antmicro"
			(at -0.95 -4.169 0)
			(layer "B.Fab")
			(effects
				(font
					(size 0.7 0.7)
					(thickness 0.15)
				)
				(justify left bottom mirror)
			)
		)
		(fp_text user "${REFERENCE}"
			(at -0.95 -3.168 0)
			(layer "B.Fab")
			(effects
				(font
					(size 0.7 0.7)
					(thickness 0.15)
				)
				(justify left bottom mirror)
			)
		)
		(pad "1" smd roundrect
			(at -0.48 0 180)
			(size 0.59 0.64)
			(layers "B.Cu" "B.Mask" "B.Paste")
			(roundrect_rratio 0.25)
			(net 553 "/HDMI/HDMI_3V3")
			(pintype "passive")
		)
		(pad "2" smd roundrect
			(at 0.48 0 180)
			(size 0.59 0.64)
			(layers "B.Cu" "B.Mask" "B.Paste")
			(roundrect_rratio 0.25)
			(net 50 "+3V3")
			(pintype "passive")
		)
	)
)
